# TIMECARD (Time Appliance Project (Time Card)) — schematic netlist excerpt (pin names and nets, part order shuffled) for the footprints in the layout excerpt that follows; sources: Cadence DE-HDL packaged netlist, KiCad conversion of R4006-B0001-02_R01.brd

U36  LM75BDP_TSSOP8  pkg SOP8_118_P0256_V2  page 17
  SDA  = R_LM75B_3_I2C_SDA
  SCL  = LM75B_I2C_SCL
  OS  = FPGA_IN_LM75B_INT3_N
  GND  = SG
  A2  = UNNAMED_6_LM75BDPTSSOP8_I81_A2
  A1  = UNNAMED_6_LM75BDPTSSOP8_I81_A1
  A0  = UNNAMED_6_LM75BDPTSSOP8_I81_A0
  VCC  = XP3R3V_FPGA

(kicad_pcb
	(version 20260206)
	(generator "pcbnew")
	(generator_version "10.0")
	(general
		(thickness 1.6)
		(legacy_teardrops no)
	)
	(paper "A4")
	(title_block
		(title "timecard-production-celestica-r4006 — R4006-B0001-02_R01.brd")
		(comment 1 "Time Appliance Project (Time Card) / footprints 99-99 of 1113")
	)
	(layers
		(0 "F.Cu" signal "TOP")
		(4 "In1.Cu" signal "L02_GND1")
		(6 "In2.Cu" signal "L03_SIG1")
		(8 "In3.Cu" signal "L04_GND2")
		(10 "In4.Cu" signal "L05_VCC1")
		(12 "In5.Cu" signal "L06_VCC2")
		(14 "In6.Cu" signal "L07_GND3")
		(16 "In7.Cu" signal "L08_SIG2")
		(18 "In8.Cu" signal "L09_GND4")
		(2 "B.Cu" signal "BOTTOM")
		(9 "F.Adhes" user "F.Adhesive")
		(11 "B.Adhes" user "B.Adhesive")
		(13 "F.Paste" user "Package Geometry/Pastemask Top")
		(15 "B.Paste" user "Package Geometry/Pastemask Bottom")
		(5 "F.SilkS" user "Ref Des/Silkscreen Top")
		(7 "B.SilkS" user "Ref Des/Silkscreen Bottom")
		(1 "F.Mask" user "Board Geometry/Soldermask Top")
		(3 "B.Mask" user "Board Geometry/Soldermask Bottom")
		(17 "Dwgs.User" user "User.Drawings")
		(19 "Cmts.User" user "User.Comments")
		(21 "Eco1.User" user "User.Eco1")
		(23 "Eco2.User" user "User.Eco2")
		(25 "Edge.Cuts" user "Board Geometry/Outline")
		(27 "Margin" user)
		(31 "F.CrtYd" user "Package Geometry/Place Bound Top")
		(29 "B.CrtYd" user "Package Geometry/Place Bound Bottom")
		(35 "F.Fab" user "Ref Des/Assembly Top")
		(33 "B.Fab" user "Ref Des/Assembly Bottom")
	)
	(footprint ""
		(layer "F.Cu")
		(at 156.845 -26.543)
		(property "Reference" "U36"
			(at -0.127 2.57937 0)
			(unlocked yes)
			(layer "F.SilkS")
			(effects
				(font
					(size 0.7874 0.5842)
					(thickness 0.1524)
				)
			)
		)
		(property "Value" ""
			(at 0 0 0)
			(layer "F.Fab")
			(effects
				(font
					(size 1.27 1.27)
				)
			)
		)
		(property "Device Type" "LM75BDP_TSSOP8-G220-10215-01"
			(at -0.03175 2.55651 0)
			(unlocked yes)
			(layer "F.Fab")
			(hide yes)
			(effects
				(font
					(size 0.7874 0.5842)
					(thickness 0.1524)
				)
			)
		)
		(property "User Part Number" "PARTNUM*"
			(at -0.037592 3.488182 0)
			(unlocked yes)
			(layer "Cmts.User")
			(hide yes)
			(effects
				(font
					(size 0.7874 0.5842)
					(thickness 0.1524)
				)
			)
		)
		(duplicate_pad_numbers_are_jumpers no)
		(fp_line
			(start -3.3147 -1.45796)
			(end -3.3147 1.45796)
			(stroke
				(width 0.1)
				(type default)
			)
			(layer "F.SilkS")
		)
		(fp_line
			(start -3.3147 1.45796)
			(end -1.778 1.45796)
			(stroke
				(width 0.1)
				(type default)
			)
			(layer "F.SilkS")
		)
		(fp_line
			(start -1.778 -1.778)
			(end -1.778 -1.45796)
			(stroke
				(width 0.1)
				(type default)
			)
			(layer "F.SilkS")
		)
		(fp_line
			(start -1.778 -1.45796)
			(end -3.3147 -1.45796)
			(stroke
				(width 0.1)
				(type default)
			)
			(layer "F.SilkS")
		)
		(fp_line
			(start -1.778 1.45796)
			(end -1.778 1.778)
			(stroke
				(width 0.1)
				(type default)
			)
			(layer "F.SilkS")
		)
		(fp_line
			(start -1.778 1.778)
			(end 1.778 1.778)
			(stroke
				(width 0.1)
				(type default)
			)
			(layer "F.SilkS")
		)
		(fp_line
			(start 1.778 -1.778)
			(end -1.778 -1.778)
			(stroke
				(width 0.1)
				(type default)
			)
			(layer "F.SilkS")
		)
		(fp_line
			(start 1.778 -1.45796)
			(end 1.778 -1.778)
			(stroke
				(width 0.1)
				(type default)
			)
			(layer "F.SilkS")
		)
		(fp_line
			(start 1.778 1.45796)
			(end 3.3147 1.45796)
			(stroke
				(width 0.1)
				(type default)
			)
			(layer "F.SilkS")
		)
		(fp_line
			(start 1.778 1.778)
			(end 1.778 1.45796)
			(stroke
				(width 0.1)
				(type default)
			)
			(layer "F.SilkS")
		)
		(fp_line
			(start 3.3147 -1.45796)
			(end 1.778 -1.45796)
			(stroke
				(width 0.1)
				(type default)
			)
			(layer "F.SilkS")
		)
		(fp_line
			(start 3.3147 1.45796)
			(end 3.3147 -1.45796)
			(stroke
				(width 0.1)
				(type default)
			)
			(layer "F.SilkS")
		)
		(fp_poly
			(pts
				(arc
					(start -3.175 -2.159)
					(mid -3.937 -2.159)
					(end -3.175 -2.159)
				)
			)
			(stroke
				(width 0)
				(type default)
			)
			(fill yes)
			(layer "F.SilkS")
		)
		(fp_rect
			(start -3.5687 2.032)
			(end 3.5687 -2.032)
			(stroke
				(width 0)
				(type default)
			)
			(fill no)
			(layer "F.CrtYd")
		)
		(fp_line
			(start -1.524 -1.524)
			(end 1.524 -1.524)
			(stroke
				(width 0.1)
				(type default)
			)
			(layer "F.Fab")
		)
		(fp_line
			(start -1.524 1.524)
			(end -1.524 -1.524)
			(stroke
				(width 0.1)
				(type default)
			)
			(layer "F.Fab")
		)
		(fp_line
			(start 1.524 -1.524)
			(end 1.524 1.524)
			(stroke
				(width 0.1)
				(type default)
			)
			(layer "F.Fab")
		)
		(fp_line
			(start 1.524 1.524)
			(end -1.524 1.524)
			(stroke
				(width 0.1)
				(type default)
			)
			(layer "F.Fab")
		)
		(fp_poly
			(pts
				(arc
					(start -0.6096 -0.9398)
					(mid -1.3716 -0.9398)
					(end -0.6096 -0.9398)
				)
			)
			(stroke
				(width 0)
				(type default)
			)
			(fill yes)
			(layer "F.Fab")
		)
		(fp_text user "5"
			(at 3.556 2.70637 0)
			(unlocked yes)
			(layer "F.SilkS")
			(effects
				(font
					(size 0.7874 0.5842)
					(thickness 0.1524)
				)
			)
		)
		(fp_text user "8"
			(at 3.937 -2.11963 0)
			(unlocked yes)
			(layer "F.SilkS")
			(effects
				(font
					(size 0.7874 0.5842)
					(thickness 0.1524)
				)
			)
		)
		(fp_text user "4"
			(at -1.8796 1.24587 0)
			(unlocked yes)
			(layer "F.Fab")
			(effects
				(font
					(size 0.7874 0.5842)
					(thickness 0.1524)
				)
			)
		)
		(fp_text user "8"
			(at 2.16281 -0.94996 0)
			(unlocked yes)
			(layer "F.Fab")
			(effects
				(font
					(size 0.7874 0.5842)
					(thickness 0.1524)
				)
			)
		)
		(fp_text user "5"
			(at 2.16281 1.08204 0)
			(unlocked yes)
			(layer "F.Fab")
			(effects
				(font
					(size 0.7874 0.5842)
					(thickness 0.1524)
				)
			)
		)
		(pad "1" smd rect
			(at -2.2987 -0.97536 90)
			(size 0.4572 1.524)
			(layers "F.Cu" "F.Mask" "F.Paste")
			(net "R_LM75B_3_I2C_SDA")
		)
		(pad "2" smd rect
			(at -2.2987 -0.32512 90)
			(size 0.4572 1.524)
			(layers "F.Cu" "F.Mask" "F.Paste")
			(net "LM75B_I2C_SCL")
		)
		(pad "3" smd rect
			(at -2.2987 0.32512 90)
			(size 0.4572 1.524)
			(layers "F.Cu" "F.Mask" "F.Paste")
			(net "FPGA_IN_LM75B_INT3_N")
		)
		(pad "4" smd rect
			(at -2.2987 0.97536 90)
			(size 0.4572 1.524)
			(layers "F.Cu" "F.Mask" "F.Paste")
			(net "SG")
		)
		(pad "5" smd rect
			(at 2.2987 0.97536 90)
			(size 0.4572 1.524)
			(layers "F.Cu" "F.Mask" "F.Paste")
			(net "UNNAMED_6_LM75BDPTSSOP8_I81_A2")
		)
		(pad "6" smd rect
			(at 2.2987 0.32512 90)
			(size 0.4572 1.524)
			(layers "F.Cu" "F.Mask" "F.Paste")
			(net "UNNAMED_6_LM75BDPTSSOP8_I81_A1")
		)
		(pad "7" smd rect
			(at 2.2987 -0.32512 90)
			(size 0.4572 1.524)
			(layers "F.Cu" "F.Mask" "F.Paste")
			(net "UNNAMED_6_LM75BDPTSSOP8_I81_A0")
		)
		(pad "8" smd rect
			(at 2.2987 -0.97536 90)
			(size 0.4572 1.524)
			(layers "F.Cu" "F.Mask" "F.Paste")
			(net "XP3R3V_FPGA")
		)
	)
)
